# BASEBOARD_FAB2 (Tioga Pass) — schematic netlist excerpt (pin names and nets, part order shuffled) for the footprints in the layout excerpt that follows; sources: Cadence DE-HDL packaged netlist, KiCad conversion of Wiwynn_Tioga_Pass_MB.brd

R2T17  RES  0.0 5% CHIP  pkg 0402  page 93 : A = H_CPU0_ERR0_G_N ; B = H_CPU_ERR0_GTL_R_N
C7U4  CAP  10UF 4V 20% X6S  pkg 0603LF  page 233 : A = PVPP_GHJ ; B = GND
C9N21  CAP  10UF 16V 10% X6S  pkg 0805  page 210 : A = VR_FET_SW_P12V_STBY_PVCCIN_CPU1 ; B = GND

(kicad_pcb
	(version 20260206)
	(generator "pcbnew")
	(generator_version "10.0")
	(general
		(thickness 1.6)
		(legacy_teardrops no)
	)
	(paper "A4")
	(title_block
		(title "Wiwynn_Tioga_Pass_MB.brd")
		(comment 1 "Tioga Pass / footprints 3525-3527 of 4770")
	)
	(layers
		(0 "F.Cu" signal "TOP")
		(4 "In1.Cu" signal "L2GND")
		(6 "In2.Cu" signal "L3")
		(8 "In3.Cu" signal "L4GND")
		(10 "In4.Cu" signal "L5")
		(12 "In5.Cu" signal "L6GND")
		(14 "In6.Cu" signal "L7VCC")
		(16 "In7.Cu" signal "L8VCC")
		(18 "In8.Cu" signal "L9GND")
		(20 "In9.Cu" signal "L10")
		(22 "In10.Cu" signal "L11GND")
		(24 "In11.Cu" signal "L12")
		(26 "In12.Cu" signal "L13GND")
		(2 "B.Cu" signal "BOTTOM")
		(9 "F.Adhes" user "F.Adhesive")
		(11 "B.Adhes" user "B.Adhesive")
		(13 "F.Paste" user "Package Geometry/Pastemask Top")
		(15 "B.Paste" user "Package Geometry/Pastemask Bottom")
		(5 "F.SilkS" user "Ref Des/Silkscreen Top")
		(7 "B.SilkS" user "Ref Des/Silkscreen Bottom")
		(1 "F.Mask" user "Board Geometry/Soldermask Top")
		(3 "B.Mask" user "Board Geometry/Soldermask Bottom")
		(17 "Dwgs.User" user "User.Drawings")
		(19 "Cmts.User" user "User.Comments")
		(21 "Eco1.User" user "User.Eco1")
		(23 "Eco2.User" user "User.Eco2")
		(25 "Edge.Cuts" user "Board Geometry/Outline")
		(27 "Margin" user)
		(31 "F.CrtYd" user "Package Geometry/Place Bound Top")
		(29 "B.CrtYd" user "Package Geometry/Place Bound Bottom")
		(35 "F.Fab" user "Ref Des/Assembly Top")
		(33 "B.Fab" user "Ref Des/Assembly Bottom")
	)
	(footprint ""
		(layer "B.Cu")
		(at 153.543 -8.128 -90)
		(property "Reference" "C7U4"
			(at 0 0 90)
			(layer "B.SilkS")
			(hide yes)
			(effects
				(font
					(size 1.27 1.27)
				)
				(justify mirror)
			)
		)
		(property "Value" ""
			(at 0 0 90)
			(layer "B.Fab")
			(effects
				(font
					(size 1.27 1.27)
				)
				(justify mirror)
			)
		)
		(duplicate_pad_numbers_are_jumpers no)
		(fp_poly
			(pts
				(xy 0.4953 -0.2032) (xy -0.4953 -0.2032) (xy -0.4953 1.6002) (xy 0.4953 1.6002)
			)
			(stroke
				(width 0)
				(type default)
			)
			(fill no)
			(layer "B.CrtYd")
		)
		(fp_line
			(start -0.4953 1.6002)
			(end 0.4953 1.6002)
			(stroke
				(width 0.1)
				(type default)
			)
			(layer "B.Fab")
		)
		(fp_line
			(start 0.4953 1.6002)
			(end 0.4953 -0.2032)
			(stroke
				(width 0.1)
				(type default)
			)
			(layer "B.Fab")
		)
		(fp_line
			(start -0.4953 -0.2032)
			(end -0.4953 1.6002)
			(stroke
				(width 0.1)
				(type default)
			)
			(layer "B.Fab")
		)
		(fp_line
			(start 0.4953 -0.2032)
			(end -0.4953 -0.2032)
			(stroke
				(width 0.1)
				(type default)
			)
			(layer "B.Fab")
		)
		(pad "1" smd rect
			(at 0 0 90)
			(size 0.762 0.889)
			(layers "B.Cu" "B.Mask" "B.Paste")
			(net "PVPP_GHJ")
		)
		(pad "2" smd rect
			(at 0 1.397 90)
			(size 0.762 0.889)
			(layers "B.Cu" "B.Mask" "B.Paste")
			(net "GND")
		)
		(zone
			(layer "B.Cu")
			(hatch none 0.5)
			(connect_pads
				(clearance 0)
			)
			(min_thickness 0.25)
			(keepout
				(tracks not_allowed)
				(vias allowed)
				(pads allowed)
				(copperpour not_allowed)
				(footprints allowed)
			)
			(placement
				(enabled no)
				(sheetname "")
			)
			(fill
				(thermal_gap 0.5)
				(thermal_bridge_width 0.5)
				(island_removal_mode 0)
			)
			(polygon
				(pts
					(xy 153.0985 -7.747) (xy 153.0985 -8.509) (xy 152.5905 -8.509) (xy 152.5905 -7.747)
				)
			)
		)
	)
	(footprint ""
		(layer "B.Cu")
		(at 32.832802 -100.613464 90)
		(property "Reference" "C9N21"
			(at 0 0 90)
			(layer "B.SilkS")
			(hide yes)
			(effects
				(font
					(size 1.27 1.27)
				)
				(justify mirror)
			)
		)
		(property "Value" ""
			(at 0 0 90)
			(layer "B.Fab")
			(effects
				(font
					(size 1.27 1.27)
				)
				(justify mirror)
			)
		)
		(duplicate_pad_numbers_are_jumpers no)
		(fp_poly
			(pts
				(xy 0.7239 -0.2159) (xy -0.7239 -0.2159) (xy -0.7239 1.9939) (xy 0.7239 1.9939)
			)
			(stroke
				(width 0)
				(type default)
			)
			(fill no)
			(layer "B.CrtYd")
		)
		(fp_line
			(start 0.7239 -0.2159)
			(end 0.7239 1.9939)
			(stroke
				(width 0.1)
				(type default)
			)
			(layer "B.Fab")
		)
		(fp_line
			(start -0.7239 -0.2159)
			(end 0.7239 -0.2159)
			(stroke
				(width 0.1)
				(type default)
			)
			(layer "B.Fab")
		)
		(fp_line
			(start 0.7239 1.9939)
			(end -0.7239 1.9939)
			(stroke
				(width 0.1)
				(type default)
			)
			(layer "B.Fab")
		)
		(fp_line
			(start -0.7239 1.9939)
			(end -0.7239 -0.2159)
			(stroke
				(width 0.1)
				(type default)
			)
			(layer "B.Fab")
		)
		(pad "1" smd rect
			(at 0 0 270)
			(size 1.27 1.016)
			(layers "B.Cu" "B.Mask" "B.Paste")
			(net "VR_FET_SW_P12V_STBY_PVCCIN_CPU1")
		)
		(pad "2" smd rect
			(at 0 1.778 270)
			(size 1.27 1.016)
			(layers "B.Cu" "B.Mask" "B.Paste")
			(net "GND")
		)
		(zone
			(layer "B.Cu")
			(hatch none 0.5)
			(connect_pads
				(clearance 0)
			)
			(min_thickness 0.25)
			(keepout
				(tracks not_allowed)
				(vias allowed)
				(pads allowed)
				(copperpour not_allowed)
				(footprints allowed)
			)
			(placement
				(enabled no)
				(sheetname "")
			)
			(fill
				(thermal_gap 0.5)
				(thermal_bridge_width 0.5)
				(island_removal_mode 0)
			)
			(polygon
				(pts
					(xy 33.340802 -101.248464) (xy 33.340802 -99.978464) (xy 34.102802 -99.978464) (xy 34.102802 -101.248464)
				)
			)
		)
	)
	(footprint ""
		(layer "B.Cu")
		(at 375.062242 -41.424352 -90)
		(property "Reference" "R2T17"
			(at 0 0 90)
			(layer "B.SilkS")
			(hide yes)
			(effects
				(font
					(size 1.27 1.27)
				)
				(justify mirror)
			)
		)
		(property "Value" ""
			(at 0 0 90)
			(layer "B.Fab")
			(effects
				(font
					(size 1.27 1.27)
				)
				(justify mirror)
			)
		)
		(duplicate_pad_numbers_are_jumpers no)
		(fp_poly
			(pts
				(xy 0.2794 -0.1016) (xy -0.2794 -0.1016) (xy -0.2794 0.9906) (xy 0.2794 0.9906)
			)
			(stroke
				(width 0)
				(type default)
			)
			(fill no)
			(layer "B.CrtYd")
		)
		(fp_line
			(start -0.2794 0.9906)
			(end -0.2794 -0.1016)
			(stroke
				(width 0.1)
				(type default)
			)
			(layer "B.Fab")
		)
		(fp_line
			(start 0.2794 0.9906)
			(end -0.2794 0.9906)
			(stroke
				(width 0.1)
				(type default)
			)
			(layer "B.Fab")
		)
		(fp_line
			(start -0.2794 -0.1016)
			(end 0.2794 -0.1016)
			(stroke
				(width 0.1)
				(type default)
			)
			(layer "B.Fab")
		)
		(fp_line
			(start 0.2794 -0.1016)
			(end 0.2794 0.9906)
			(stroke
				(width 0.1)
				(type default)
			)
			(layer "B.Fab")
		)
		(pad "1" smd rect
			(at 0 0 90)
			(size 0.508 0.508)
			(layers "B.Cu" "B.Mask" "B.Paste")
			(net "H_CPU0_ERR0_G_N")
		)
		(pad "2" smd rect
			(at 0 0.889 90)
			(size 0.508 0.508)
			(layers "B.Cu" "B.Mask" "B.Paste")
			(net "H_CPU_ERR0_GTL_R_N")
		)
		(zone
			(layer "B.Cu")
			(hatch none 0.5)
			(connect_pads
				(clearance 0)
			)
			(min_thickness 0.25)
			(keepout
				(tracks not_allowed)
				(vias allowed)
				(pads allowed)
				(copperpour not_allowed)
				(footprints allowed)
			)
			(placement
				(enabled no)
				(sheetname "")
			)
			(fill
				(thermal_gap 0.5)
				(thermal_bridge_width 0.5)
				(island_removal_mode 0)
			)
			(polygon
				(pts
					(xy 374.427242 -41.170352) (xy 374.427242 -41.678352) (xy 374.808242 -41.678352) (xy 374.808242 -41.170352)
				)
			)
		)
		(zone
			(layer "B.Cu")
			(hatch none 0.5)
			(connect_pads
				(clearance 0)
			)
			(min_thickness 0.25)
			(keepout
				(tracks allowed)
				(vias not_allowed)
				(pads allowed)
				(copperpour not_allowed)
				(footprints allowed)
			)
			(placement
				(enabled no)
				(sheetname "")
			)
			(fill
				(thermal_gap 0.5)
				(thermal_bridge_width 0.5)
				(island_removal_mode 0)
			)
			(polygon
				(pts
					(xy 374.808242 -41.170352) (xy 374.808242 -41.678352) (xy 374.427242 -41.678352) (xy 374.427242 -41.170352)
				)
			)
		)
	)
)
